FILE_TYPE = MACRO_DRAWING;
SET COLOR_WIRE YELLOW;
SET COLOR_PROP ORANGE;
SET COLOR_DOT WHITE;
SET COLOR_ARC YELLOW;
SET COLOR_BODY GREEN;
SET COLOR_NOTE PURPLE;
SET PROP_DISPLAY VALUE;
SET PAGE_NUMBER P122;
FORCEADD OFFPAGE..1
(-3075 2175);
FORCEPROP 2 LAST $XR0 14 
J 0
(-3296 2175);
DISPLAY 0.638298 (-3296 2175);
PAINT MONO (-3296 2175);
FORCEPROP 1 LAST COMMENT_BODY TRUE
J 0
(-2950 2075);
DISPLAY 0.872340 (-2950 2075);
PAINT GREEN (-2950 2075);
DISPLAY INVISIBLE (-2950 2075);
FORCEPROP 1 LAST OFFPAGE TRUE
J 0
(-2750 2050);
DISPLAY 0.872340 (-2750 2050);
PAINT GREEN (-2750 2050);
DISPLAY INVISIBLE (-2750 2050);
FORCEPROP 2 LAST CDS_LIB standard
J 0
(-3075 2175);
PAINT MONO (-3075 2175);
DISPLAY INVISIBLE (-3075 2175);
FORCEPROP 2 LAST PATH I1
J 0
(-3275 2225);
DISPLAY 1.021277 (-3275 2225);
DISPLAY INVISIBLE (-3275 2225);
FORCEADD BC847BPN..2
(-650 825);
FORCEPROP 1 LAST PART_NUMBER BA008470026
J 0
(-595 669);
DISPLAY 0.723404 (-595 669);
PAINT GREEN (-595 669);
DISPLAY INVISIBLE (-595 669);
FORCEPROP 2 LAST PART_TYPE SMLF
J 0
(-575 875);
DISPLAY 1.021277 (-575 875);
FORCEPROP 1 LAST MATERIAL IC
J 0
(-595 582);
DISPLAY 0.723404 (-595 582);
PAINT GREEN (-595 582);
FORCEPROP 2 LAST VALUE BC847BPN
J 0
(-575 825);
DISPLAY 1.021277 (-575 825);
FORCEPROP 1 LAST LOCATION Q142
J 0
(-595 776);
DISPLAY 0.723404 (-595 776);
PAINT GREEN (-595 776);
FORCEPROP 0 LASTPIN (-750 825) $PN 5
J 2
(-760 835);
DISPLAY 0.680851 (-760 835);
PAINT MONO (-760 835);
FORCEPROP 0 LASTPIN (-600 725) $PN 3
R 1
J 2
(-610 715);
DISPLAY 0.680851 (-610 715);
PAINT MONO (-610 715);
FORCEPROP 0 LASTPIN (-600 925) $PN 4
R 1
J 0
(-610 935);
DISPLAY 0.680851 (-610 935);
PAINT MONO (-610 935);
FORCEPROP 1 LAST CDS_LMAN_SYM_OUTLINE -50,50,50,-50
J 0
(-650 825);
DISPLAY 0.468085 (-650 825);
PAINT GREEN (-650 825);
DISPLAY INVISIBLE (-650 825);
FORCEPROP 1 LAST NEEDS_NO_SIZE TRUE
J 0
(-650 825);
DISPLAY 0.723404 (-650 825);
PAINT GREEN (-650 825);
DISPLAY INVISIBLE (-650 825);
FORCEPROP 2 LAST CDS_LIB pure_quanta
J 0
(-650 825);
DISPLAY INVISIBLE (-650 825);
FORCEPROP 1 LAST PATH I10
J 0
(-650 825);
DISPLAY 0.723404 (-650 825);
PAINT GREEN (-650 825);
DISPLAY INVISIBLE (-650 825);
FORCEPROP 0 LAST $SEC 2
J 0
(-575 925);
DISPLAY 0.680851 (-575 925);
PAINT MONO (-575 925);
DISPLAY INVISIBLE (-575 925);
FORCEPROP 0 LAST CDS_SEC 2
J 0
(-575 925);
DISPLAY 1.021277 (-575 925);
DISPLAY INVISIBLE (-575 925);
FORCEADD UNIVERSAL_POWER..1
(-600 1075);
FORCEPROP 3 LASTPIN (-600 1025) SIG_NAME PVNN_TERM_CPU1\g
J 0
(-590 1035);
DISPLAY 0.659574 (-590 1035);
PAINT MONO (-590 1035);
DISPLAY INVISIBLE (-590 1035);
FORCEPROP 1 LAST HDL_POWER PVNN_TERM_CPU1
J 1
(-600 1125);
DISPLAY 0.872340 (-600 1125);
PAINT GREEN (-600 1125);
FORCEPROP 2 LAST CDS_LIB logical_power
J 0
(-600 1075);
DISPLAY INVISIBLE (-600 1075);
FORCEPROP 1 LAST PATH I11
J 0
(-550 1100);
DISPLAY 0.872340 (-550 1100);
PAINT AQUA (-550 1100);
DISPLAY INVISIBLE (-550 1100);
FORCEADD BC847BPN..2
(-650 2175);
FORCEPROP 1 LAST PART_NUMBER BA008470026
J 0
(-595 2019);
DISPLAY 0.723404 (-595 2019);
PAINT GREEN (-595 2019);
DISPLAY INVISIBLE (-595 2019);
FORCEPROP 2 LAST VALUE BC847BPN
J 0
(-575 2175);
DISPLAY 1.021277 (-575 2175);
FORCEPROP 1 LAST MATERIAL IC
J 0
(-595 1932);
DISPLAY 0.723404 (-595 1932);
PAINT GREEN (-595 1932);
FORCEPROP 2 LAST PART_TYPE SMLF
J 0
(-575 2225);
DISPLAY 1.021277 (-575 2225);
FORCEPROP 1 LAST LOCATION Q143
J 0
(-595 2126);
DISPLAY 0.723404 (-595 2126);
PAINT GREEN (-595 2126);
FORCEPROP 0 LASTPIN (-750 2175) $PN 5
J 2
(-760 2185);
DISPLAY 0.680851 (-760 2185);
PAINT MONO (-760 2185);
FORCEPROP 0 LASTPIN (-600 2075) $PN 3
R 1
J 2
(-610 2065);
DISPLAY 0.680851 (-610 2065);
PAINT MONO (-610 2065);
FORCEPROP 0 LASTPIN (-600 2275) $PN 4
R 1
J 0
(-610 2285);
DISPLAY 0.680851 (-610 2285);
PAINT MONO (-610 2285);
FORCEPROP 1 LAST CDS_LMAN_SYM_OUTLINE -50,50,50,-50
J 0
(-650 2175);
DISPLAY 0.468085 (-650 2175);
PAINT GREEN (-650 2175);
DISPLAY INVISIBLE (-650 2175);
FORCEPROP 1 LAST NEEDS_NO_SIZE TRUE
J 0
(-650 2175);
DISPLAY 0.723404 (-650 2175);
PAINT GREEN (-650 2175);
DISPLAY INVISIBLE (-650 2175);
FORCEPROP 2 LAST CDS_LIB pure_quanta
J 0
(-650 2175);
DISPLAY INVISIBLE (-650 2175);
FORCEPROP 1 LAST PATH I12
J 0
(-650 2175);
DISPLAY 0.723404 (-650 2175);
PAINT GREEN (-650 2175);
DISPLAY INVISIBLE (-650 2175);
FORCEPROP 0 LAST $SEC 2
J 0
(-575 2275);
DISPLAY 0.680851 (-575 2275);
PAINT MONO (-575 2275);
DISPLAY INVISIBLE (-575 2275);
FORCEPROP 0 LAST CDS_SEC 2
J 0
(-575 2275);
DISPLAY 1.021277 (-575 2275);
DISPLAY INVISIBLE (-575 2275);
FORCEADD UNIVERSAL_POWER..1
(-600 2425);
FORCEPROP 3 LASTPIN (-600 2375) SIG_NAME PVNN_TERM_CPU0\g
J 0
(-590 2385);
DISPLAY 0.659574 (-590 2385);
PAINT MONO (-590 2385);
DISPLAY INVISIBLE (-590 2385);
FORCEPROP 1 LAST HDL_POWER PVNN_TERM_CPU0
J 1
(-600 2475);
DISPLAY 0.872340 (-600 2475);
PAINT GREEN (-600 2475);
FORCEPROP 2 LAST CDS_LIB logical_power
J 0
(-600 2425);
DISPLAY INVISIBLE (-600 2425);
FORCEPROP 1 LAST PATH I13
J 0
(-550 2450);
DISPLAY 0.872340 (-550 2450);
PAINT AQUA (-550 2450);
DISPLAY INVISIBLE (-550 2450);
FORCEADD UNIVERSAL_POWER..1
(-2000 2650);
FORCEPROP 3 LASTPIN (-2000 2600) SIG_NAME PVNN_TERM_CPU0\g
J 0
(-1990 2610);
DISPLAY 0.659574 (-1990 2610);
PAINT MONO (-1990 2610);
DISPLAY INVISIBLE (-1990 2610);
FORCEPROP 1 LAST HDL_POWER PVNN_TERM_CPU0
J 1
(-2000 2700);
DISPLAY 0.872340 (-2000 2700);
PAINT GREEN (-2000 2700);
FORCEPROP 2 LAST CDS_LIB logical_power
J 0
(-2000 2650);
DISPLAY INVISIBLE (-2000 2650);
FORCEPROP 1 LAST PATH I14
J 0
(-1950 2675);
DISPLAY 0.872340 (-1950 2675);
PAINT AQUA (-1950 2675);
DISPLAY INVISIBLE (-1950 2675);
FORCEADD Q_RES..1
(-1475 3400);
FORCEPROP 1 LAST PART_NUMBER CS00002JB13
J 0
(-1575 3475);
DISPLAY 0.510638 (-1575 3475);
DISPLAY INVISIBLE (-1575 3475);
FORCEPROP 1 LAST PACK_TYPE 0402LF
J 0
(-1225 3400);
DISPLAY 0.638298 (-1225 3400);
FORCEPROP 1 LAST WATTAGE 1/16W
J 2
(-1350 3525);
DISPLAY 0.510638 (-1350 3525);
FORCEPROP 1 LAST TOLERANCE 5%
J 0
(-1300 3400);
DISPLAY 0.638298 (-1300 3400);
FORCEPROP 1 LAST VALUE 0
J 2
(-1325 3400);
DISPLAY 0.638298 (-1325 3400);
FORCEPROP 1 LAST MATERIAL CHIP
J 0
(-1575 3525);
DISPLAY 0.510638 (-1575 3525);
FORCEPROP 1 LAST $LOCATION R210
J 0
(-1675 3400);
DISPLAY 0.638298 (-1675 3400);
FORCEPROP 1 LASTPIN (-1575 3400) $PN 1
J 0
(-1563 3412);
DISPLAY 0.787234 (-1563 3412);
FORCEPROP 1 LASTPIN (-1375 3400) $PN 2
J 0
(-1413 3412);
DISPLAY 0.787234 (-1413 3412);
FORCEPROP 2 LAST CDS_LIB pure_quanta
J 0
(-1475 3400);
PAINT MONO (-1475 3400);
DISPLAY INVISIBLE (-1475 3400);
FORCEPROP 1 LAST PATH I15
J 0
(-1525 3550);
DISPLAY 0.978723 (-1525 3550);
PAINT WHITE (-1525 3550);
DISPLAY INVISIBLE (-1525 3550);
FORCEPROP 2 LAST CDS_LOCATION R210
J 0
(-1525 3600);
DISPLAY 1.021277 (-1525 3600);
DISPLAY INVISIBLE (-1525 3600);
FORCEPROP 2 LAST $SEC 1
J 0
(-1525 3600);
DISPLAY 0.680851 (-1525 3600);
PAINT MONO (-1525 3600);
DISPLAY INVISIBLE (-1525 3600);
FORCEPROP 2 LAST CDS_SEC 1
J 0
(-1525 3600);
DISPLAY 1.021277 (-1525 3600);
DISPLAY INVISIBLE (-1525 3600);
FORCEADD Q_RES..1
(-1475 4350);
FORCEPROP 1 LAST PART_NUMBER CS00002JB13
J 0
(-1575 4425);
DISPLAY 0.510638 (-1575 4425);
DISPLAY INVISIBLE (-1575 4425);
FORCEPROP 1 LAST PACK_TYPE 0402LF
J 0
(-1225 4350);
DISPLAY 0.638298 (-1225 4350);
FORCEPROP 1 LAST TOLERANCE 5%
J 0
(-1300 4350);
DISPLAY 0.638298 (-1300 4350);
FORCEPROP 1 LAST MATERIAL CHIP
J 0
(-1575 4475);
DISPLAY 0.510638 (-1575 4475);
FORCEPROP 1 LAST WATTAGE 1/16W
J 2
(-1350 4475);
DISPLAY 0.510638 (-1350 4475);
FORCEPROP 1 LAST VALUE 0
J 2
(-1325 4350);
DISPLAY 0.638298 (-1325 4350);
FORCEPROP 1 LAST $LOCATION R208
J 0
(-1675 4350);
DISPLAY 0.638298 (-1675 4350);
FORCEPROP 1 LASTPIN (-1575 4350) $PN 1
J 0
(-1563 4362);
DISPLAY 0.787234 (-1563 4362);
FORCEPROP 1 LASTPIN (-1375 4350) $PN 2
J 0
(-1413 4362);
DISPLAY 0.787234 (-1413 4362);
FORCEPROP 2 LAST CDS_LIB pure_quanta
J 0
(-1475 4350);
PAINT MONO (-1475 4350);
DISPLAY INVISIBLE (-1475 4350);
FORCEPROP 1 LAST PATH I16
J 0
(-1525 4500);
DISPLAY 0.978723 (-1525 4500);
PAINT WHITE (-1525 4500);
DISPLAY INVISIBLE (-1525 4500);
FORCEPROP 2 LAST CDS_LOCATION R208
J 0
(-1525 4550);
DISPLAY 1.021277 (-1525 4550);
DISPLAY INVISIBLE (-1525 4550);
FORCEPROP 2 LAST $SEC 1
J 0
(-1525 4550);
DISPLAY 0.680851 (-1525 4550);
PAINT MONO (-1525 4550);
DISPLAY INVISIBLE (-1525 4550);
FORCEPROP 2 LAST CDS_SEC 1
J 0
(-1525 4550);
DISPLAY 1.021277 (-1525 4550);
DISPLAY INVISIBLE (-1525 4550);
FORCEADD BC847BPN..1
(900 575);
FORCEPROP 1 LAST PART_NUMBER BA008470026
J 0
(955 419);
DISPLAY 0.723404 (955 419);
PAINT GREEN (955 419);
DISPLAY INVISIBLE (955 419);
FORCEPROP 2 LAST VALUE BC847BPN
J 0
(975 575);
DISPLAY 1.021277 (975 575);
FORCEPROP 2 LAST PART_TYPE SMLF
J 0
(975 625);
DISPLAY 1.021277 (975 625);
FORCEPROP 1 LAST MATERIAL IC
J 0
(955 332);
DISPLAY 0.723404 (955 332);
PAINT GREEN (955 332);
FORCEPROP 1 LAST LOCATION Q142
J 0
(955 526);
DISPLAY 0.723404 (955 526);
PAINT GREEN (955 526);
FORCEPROP 0 LASTPIN (800 575) $PN 2
J 2
(790 585);
DISPLAY 0.680851 (790 585);
PAINT MONO (790 585);
FORCEPROP 0 LASTPIN (950 475) $PN 6
R 1
J 2
(940 465);
DISPLAY 0.680851 (940 465);
PAINT MONO (940 465);
FORCEPROP 0 LASTPIN (950 675) $PN 1
R 1
J 0
(940 685);
DISPLAY 0.680851 (940 685);
PAINT MONO (940 685);
FORCEPROP 1 LAST CDS_LMAN_SYM_OUTLINE -50,50,50,-50
J 0
(900 575);
DISPLAY 0.468085 (900 575);
PAINT GREEN (900 575);
DISPLAY INVISIBLE (900 575);
FORCEPROP 1 LAST NEEDS_NO_SIZE TRUE
J 0
(900 575);
DISPLAY 0.723404 (900 575);
PAINT GREEN (900 575);
DISPLAY INVISIBLE (900 575);
FORCEPROP 2 LAST CDS_LIB pure_quanta
J 0
(900 575);
DISPLAY INVISIBLE (900 575);
FORCEPROP 1 LAST PATH I17
J 0
(900 575);
DISPLAY 0.723404 (900 575);
PAINT GREEN (900 575);
DISPLAY INVISIBLE (900 575);
FORCEPROP 0 LAST $SEC 1
J 0
(975 675);
DISPLAY 0.680851 (975 675);
PAINT MONO (975 675);
DISPLAY INVISIBLE (975 675);
FORCEPROP 0 LAST CDS_SEC 1
J 0
(975 675);
DISPLAY 1.021277 (975 675);
DISPLAY INVISIBLE (975 675);
FORCEADD Q_RES..1
(2400 350);
FORCEPROP 1 LAST PART_NUMBER CS03322FB03
J 0
(2350 450);
DISPLAY 0.787234 (2350 450);
DISPLAY INVISIBLE (2350 450);
FORCEPROP 1 LAST VALUE 33.2
J 2
(2375 250);
DISPLAY 0.787234 (2375 250);
FORCEPROP 1 LAST PACK_TYPE 0402LF
J 0
(2650 200);
DISPLAY 0.787234 (2650 200);
FORCEPROP 1 LAST MATERIAL CHIP
J 0
(2400 200);
DISPLAY 0.787234 (2400 200);
FORCEPROP 1 LAST TOLERANCE 1%
J 0
(2400 250);
DISPLAY 0.787234 (2400 250);
FORCEPROP 1 LAST WATTAGE 1/16W
J 2
(2375 200);
DISPLAY 0.787234 (2375 200);
FORCEPROP 1 LAST $LOCATION R4408
J 0
(2175 350);
DISPLAY 0.787234 (2175 350);
FORCEPROP 1 LASTPIN (2300 350) $PN 1
J 0
(2312 362);
DISPLAY 0.787234 (2312 362);
PAINT MONO (2312 362);
FORCEPROP 1 LASTPIN (2500 350) $PN 2
J 0
(2462 362);
DISPLAY 0.787234 (2462 362);
PAINT MONO (2462 362);
FORCEPROP 2 LAST CDS_LIB pure_quanta
J 0
(2400 350);
DISPLAY INVISIBLE (2400 350);
FORCEPROP 1 LAST PATH I18
J 0
(2350 500);
DISPLAY 0.978723 (2350 500);
PAINT WHITE (2350 500);
DISPLAY INVISIBLE (2350 500);
FORCEPROP 0 LAST CDS_LOCATION R4408
J 0
(2350 500);
DISPLAY 1.021277 (2350 500);
DISPLAY INVISIBLE (2350 500);
FORCEPROP 0 LAST $SEC 1
J 0
(2350 500);
DISPLAY 0.680851 (2350 500);
PAINT MONO (2350 500);
DISPLAY INVISIBLE (2350 500);
FORCEPROP 0 LAST CDS_SEC 1
J 0
(2350 500);
DISPLAY 1.021277 (2350 500);
DISPLAY INVISIBLE (2350 500);
FORCEADD OFFPAGE..2
(3225 350);
FORCEPROP 2 LAST $XR0 216 
J 0
(3414 350);
DISPLAY 0.638298 (3414 350);
PAINT MONO (3414 350);
FORCEPROP 1 LAST COMMENT_BODY TRUE
J 0
(3180 255);
DISPLAY 0.872340 (3180 255);
PAINT GREEN (3180 255);
DISPLAY INVISIBLE (3180 255);
FORCEPROP 1 LAST OFFPAGE TRUE
J 0
(3550 225);
DISPLAY 0.872340 (3550 225);
PAINT GREEN (3550 225);
DISPLAY INVISIBLE (3550 225);
FORCEPROP 2 LAST CDS_LIB standard
J 0
(3225 350);
DISPLAY INVISIBLE (3225 350);
FORCEPROP 2 LAST PATH I19
J 0
(3425 400);
DISPLAY 1.021277 (3425 400);
DISPLAY INVISIBLE (3425 400);
FORCEADD OFFPAGE..1
(-3075 825);
FORCEPROP 2 LAST $XR0 45 
J 0
(-3296 825);
DISPLAY 0.638298 (-3296 825);
PAINT MONO (-3296 825);
FORCEPROP 1 LAST COMMENT_BODY TRUE
J 0
(-2950 725);
DISPLAY 0.872340 (-2950 725);
PAINT GREEN (-2950 725);
DISPLAY INVISIBLE (-2950 725);
FORCEPROP 1 LAST OFFPAGE TRUE
J 0
(-2750 700);
DISPLAY 0.872340 (-2750 700);
PAINT GREEN (-2750 700);
DISPLAY INVISIBLE (-2750 700);
FORCEPROP 2 LAST CDS_LIB standard
J 0
(-3075 825);
PAINT MONO (-3075 825);
DISPLAY INVISIBLE (-3075 825);
FORCEPROP 2 LAST PATH I2
J 0
(-3275 875);
DISPLAY 1.021277 (-3275 875);
DISPLAY INVISIBLE (-3275 875);
FORCEADD Q_RES..1
(125 575);
FORCEPROP 1 LAST PART_NUMBER CS21502FB07
J 0
(75 675);
DISPLAY 0.787234 (75 675);
DISPLAY INVISIBLE (75 675);
FORCEPROP 1 LAST MATERIAL CHIP
J 0
(125 425);
DISPLAY 0.638298 (125 425);
FORCEPROP 1 LAST PACK_TYPE 0402LF
J 0
(225 475);
DISPLAY 0.638298 (225 475);
FORCEPROP 1 LAST VALUE 1.5K
J 2
(100 475);
DISPLAY 0.638298 (100 475);
FORCEPROP 1 LAST $LOCATION R4404
J 0
(-75 575);
DISPLAY 0.638298 (-75 575);
FORCEPROP 1 LASTPIN (25 575) $PN 1
J 0
(37 587);
DISPLAY 0.787234 (37 587);
PAINT MONO (37 587);
FORCEPROP 1 LASTPIN (225 575) $PN 2
J 0
(187 587);
DISPLAY 0.787234 (187 587);
PAINT MONO (187 587);
FORCEPROP 1 LAST WATTAGE 1/16W
J 2
(100 425);
DISPLAY 0.638298 (100 425);
DISPLAY INVISIBLE (100 425);
FORCEPROP 1 LAST TOLERANCE 1%
J 0
(125 475);
DISPLAY 0.638298 (125 475);
DISPLAY INVISIBLE (125 475);
FORCEPROP 2 LAST CDS_LIB pure_quanta
J 0
(125 575);
DISPLAY INVISIBLE (125 575);
FORCEPROP 1 LAST PATH I20
J 0
(75 725);
DISPLAY 0.978723 (75 725);
PAINT WHITE (75 725);
DISPLAY INVISIBLE (75 725);
FORCEPROP 0 LAST CDS_LOCATION R4404
J 0
(-50 625);
DISPLAY 1.021277 (-50 625);
DISPLAY INVISIBLE (-50 625);
FORCEPROP 0 LAST $SEC 1
J 0
(-50 625);
DISPLAY 0.680851 (-50 625);
PAINT MONO (-50 625);
DISPLAY INVISIBLE (-50 625);
FORCEPROP 0 LAST CDS_SEC 1
J 0
(-50 625);
DISPLAY 1.021277 (-50 625);
DISPLAY INVISIBLE (-50 625);
FORCEADD Q_RES..1
(125 1925);
FORCEPROP 1 LAST PART_NUMBER CS21502FB07
J 0
(75 2025);
DISPLAY 0.787234 (75 2025);
DISPLAY INVISIBLE (75 2025);
FORCEPROP 1 LAST PACK_TYPE 0402LF
J 0
(225 1825);
DISPLAY 0.638298 (225 1825);
FORCEPROP 1 LAST VALUE 1.5K
J 2
(100 1825);
DISPLAY 0.638298 (100 1825);
FORCEPROP 1 LAST MATERIAL CHIP
J 0
(125 1775);
DISPLAY 0.638298 (125 1775);
FORCEPROP 1 LAST $LOCATION R4403
J 0
(-75 1925);
DISPLAY 0.638298 (-75 1925);
FORCEPROP 1 LASTPIN (25 1925) $PN 1
J 0
(37 1937);
DISPLAY 0.787234 (37 1937);
PAINT MONO (37 1937);
FORCEPROP 1 LASTPIN (225 1925) $PN 2
J 0
(187 1937);
DISPLAY 0.787234 (187 1937);
PAINT MONO (187 1937);
FORCEPROP 1 LAST WATTAGE 1/16W
J 2
(100 1775);
DISPLAY 0.638298 (100 1775);
DISPLAY INVISIBLE (100 1775);
FORCEPROP 1 LAST TOLERANCE 1%
J 0
(125 1825);
DISPLAY 0.638298 (125 1825);
DISPLAY INVISIBLE (125 1825);
FORCEPROP 2 LAST CDS_LIB pure_quanta
J 0
(125 1925);
DISPLAY INVISIBLE (125 1925);
FORCEPROP 1 LAST PATH I21
J 0
(75 2075);
DISPLAY 0.978723 (75 2075);
PAINT WHITE (75 2075);
DISPLAY INVISIBLE (75 2075);
FORCEPROP 0 LAST CDS_LOCATION R4403
J 0
(-50 1975);
DISPLAY 1.021277 (-50 1975);
DISPLAY INVISIBLE (-50 1975);
FORCEPROP 0 LAST $SEC 1
J 0
(-50 1975);
DISPLAY 0.680851 (-50 1975);
PAINT MONO (-50 1975);
DISPLAY INVISIBLE (-50 1975);
FORCEPROP 0 LAST CDS_SEC 1
J 0
(-50 1975);
DISPLAY 1.021277 (-50 1975);
DISPLAY INVISIBLE (-50 1975);
FORCEADD BC847BPN..1
(900 1925);
FORCEPROP 1 LAST PART_NUMBER BA008470026
J 0
(955 1769);
DISPLAY 0.723404 (955 1769);
PAINT GREEN (955 1769);
DISPLAY INVISIBLE (955 1769);
FORCEPROP 2 LAST VALUE BC847BPN
J 0
(975 1925);
DISPLAY 1.021277 (975 1925);
FORCEPROP 2 LAST PART_TYPE SMLF
J 0
(975 1975);
DISPLAY 1.021277 (975 1975);
FORCEPROP 1 LAST MATERIAL IC
J 0
(955 1682);
DISPLAY 0.723404 (955 1682);
PAINT GREEN (955 1682);
FORCEPROP 1 LAST LOCATION Q143
J 0
(955 1876);
DISPLAY 0.723404 (955 1876);
PAINT GREEN (955 1876);
FORCEPROP 0 LASTPIN (800 1925) $PN 2
J 2
(790 1935);
DISPLAY 0.680851 (790 1935);
PAINT MONO (790 1935);
FORCEPROP 0 LASTPIN (950 1825) $PN 6
R 1
J 2
(940 1815);
DISPLAY 0.680851 (940 1815);
PAINT MONO (940 1815);
FORCEPROP 0 LASTPIN (950 2025) $PN 1
R 1
J 0
(940 2035);
DISPLAY 0.680851 (940 2035);
PAINT MONO (940 2035);
FORCEPROP 1 LAST CDS_LMAN_SYM_OUTLINE -50,50,50,-50
J 0
(900 1925);
DISPLAY 0.468085 (900 1925);
PAINT GREEN (900 1925);
DISPLAY INVISIBLE (900 1925);
FORCEPROP 1 LAST NEEDS_NO_SIZE TRUE
J 0
(900 1925);
DISPLAY 0.723404 (900 1925);
PAINT GREEN (900 1925);
DISPLAY INVISIBLE (900 1925);
FORCEPROP 2 LAST CDS_LIB pure_quanta
J 0
(900 1925);
DISPLAY INVISIBLE (900 1925);
FORCEPROP 1 LAST PATH I22
J 0
(900 1925);
DISPLAY 0.723404 (900 1925);
PAINT GREEN (900 1925);
DISPLAY INVISIBLE (900 1925);
FORCEPROP 0 LAST $SEC 1
J 0
(975 2025);
DISPLAY 0.680851 (975 2025);
PAINT MONO (975 2025);
DISPLAY INVISIBLE (975 2025);
FORCEPROP 0 LAST CDS_SEC 1
J 0
(975 2025);
DISPLAY 1.021277 (975 2025);
DISPLAY INVISIBLE (975 2025);
FORCEADD UNIVERSAL_GND..1
(1000 900);
FORCEPROP 3 LASTPIN (1000 950) SIG_NAME GND\g
J 0
(1010 960);
DISPLAY 0.659574 (1010 960);
PAINT MONO (1010 960);
DISPLAY INVISIBLE (1010 960);
FORCEPROP 1 LAST HDL_POWER GND
J 1
(1025 825);
DISPLAY 0.872340 (1025 825);
PAINT GREEN (1025 825);
DISPLAY INVISIBLE (1025 825);
FORCEPROP 2 LAST CDS_LIB logical_power
J 0
(1000 900);
DISPLAY INVISIBLE (1000 900);
FORCEPROP 1 LAST PATH I23
J 0
(1075 900);
DISPLAY 0.872340 (1075 900);
PAINT AQUA (1075 900);
DISPLAY INVISIBLE (1075 900);
FORCEADD Q_RES..2
(1750 725);
FORCEPROP 1 LAST PART_NUMBER CS24752FB03
J 0
(1775 600);
DISPLAY 0.978723 (1775 600);
DISPLAY INVISIBLE (1775 600);
FORCEPROP 1 LAST MATERIAL CHIP
J 0
(1790 650);
DISPLAY 0.978723 (1790 650);
FORCEPROP 1 LAST PACK_TYPE 0402LF
J 0
(1790 550);
DISPLAY 0.978723 (1790 550);
FORCEPROP 1 LAST VALUE 4.75K
J 0
(1795 800);
DISPLAY 0.978723 (1795 800);
FORCEPROP 1 LAST TOLERANCE 1%
J 0
(1795 750);
DISPLAY 0.978723 (1795 750);
FORCEPROP 1 LAST WATTAGE 1/16W
J 0
(1790 700);
DISPLAY 0.978723 (1790 700);
FORCEPROP 1 LAST $LOCATION R4406
J 0
(1795 850);
DISPLAY 0.978723 (1795 850);
FORCEPROP 1 LASTPIN (1750 825) $PN 1
J 0
(1755 787);
DISPLAY 0.787234 (1755 787);
PAINT MONO (1755 787);
FORCEPROP 1 LASTPIN (1750 625) $PN 2
J 0
(1755 635);
DISPLAY 0.787234 (1755 635);
PAINT MONO (1755 635);
FORCEPROP 2 LAST CDS_LIB pure_quanta
J 0
(1750 725);
DISPLAY INVISIBLE (1750 725);
FORCEPROP 1 LAST PATH I24
J 0
(1800 900);
DISPLAY 0.978723 (1800 900);
PAINT WHITE (1800 900);
DISPLAY INVISIBLE (1800 900);
FORCEPROP 0 LAST CDS_LOCATION R4406
J 0
(1800 900);
DISPLAY 1.021277 (1800 900);
DISPLAY INVISIBLE (1800 900);
FORCEPROP 0 LAST $SEC 1
J 0
(1800 900);
DISPLAY 0.680851 (1800 900);
PAINT MONO (1800 900);
DISPLAY INVISIBLE (1800 900);
FORCEPROP 2 LAST CDS_SEC 1
J 0
(1800 950);
DISPLAY 1.021277 (1800 950);
DISPLAY INVISIBLE (1800 950);
FORCEADD UNIVERSAL_POWER..1
(1750 975);
FORCEPROP 3 LASTPIN (1750 925) SIG_NAME P3V3\g
J 0
(1760 935);
DISPLAY 0.659574 (1760 935);
PAINT MONO (1760 935);
DISPLAY INVISIBLE (1760 935);
FORCEPROP 1 LAST HDL_POWER P3V3
J 1
(1750 1025);
DISPLAY 0.872340 (1750 1025);
PAINT GREEN (1750 1025);
FORCEPROP 2 LAST CDS_LIB logical_power
J 0
(1750 975);
PAINT MONO (1750 975);
DISPLAY INVISIBLE (1750 975);
FORCEPROP 1 LAST PATH I25
J 0
(1800 1000);
DISPLAY 0.872340 (1800 1000);
PAINT AQUA (1800 1000);
DISPLAY INVISIBLE (1800 1000);
FORCEADD UNIVERSAL_GND..1
(1000 2250);
FORCEPROP 3 LASTPIN (1000 2300) SIG_NAME GND\g
J 0
(1010 2310);
DISPLAY 0.659574 (1010 2310);
PAINT MONO (1010 2310);
DISPLAY INVISIBLE (1010 2310);
FORCEPROP 1 LAST HDL_POWER GND
J 1
(1025 2175);
DISPLAY 0.872340 (1025 2175);
PAINT GREEN (1025 2175);
DISPLAY INVISIBLE (1025 2175);
FORCEPROP 2 LAST CDS_LIB logical_power
J 0
(1000 2250);
DISPLAY INVISIBLE (1000 2250);
FORCEPROP 1 LAST PATH I26
J 0
(1075 2250);
DISPLAY 0.872340 (1075 2250);
PAINT AQUA (1075 2250);
DISPLAY INVISIBLE (1075 2250);
FORCEADD Q_RES..2
(1750 2075);
FORCEPROP 1 LAST PART_NUMBER CS24752FB03
J 0
(1775 1950);
DISPLAY 0.978723 (1775 1950);
DISPLAY INVISIBLE (1775 1950);
FORCEPROP 1 LAST PACK_TYPE 0402LF
J 0
(1790 1900);
DISPLAY 0.978723 (1790 1900);
FORCEPROP 1 LAST VALUE 4.75K
J 0
(1795 2150);
DISPLAY 0.978723 (1795 2150);
FORCEPROP 1 LAST TOLERANCE 1%
J 0
(1795 2100);
DISPLAY 0.978723 (1795 2100);
FORCEPROP 1 LAST WATTAGE 1/16W
J 0
(1790 2050);
DISPLAY 0.978723 (1790 2050);
FORCEPROP 1 LAST MATERIAL CHIP
J 0
(1790 2000);
DISPLAY 0.978723 (1790 2000);
FORCEPROP 1 LAST $LOCATION R4405
J 0
(1795 2200);
DISPLAY 0.787234 (1795 2200);
FORCEPROP 1 LASTPIN (1750 2175) $PN 1
J 0
(1755 2137);
DISPLAY 0.787234 (1755 2137);
PAINT MONO (1755 2137);
FORCEPROP 1 LASTPIN (1750 1975) $PN 2
J 0
(1755 1985);
DISPLAY 0.787234 (1755 1985);
PAINT MONO (1755 1985);
FORCEPROP 2 LAST CDS_LIB pure_quanta
J 0
(1750 2075);
DISPLAY INVISIBLE (1750 2075);
FORCEPROP 1 LAST PATH I27
J 0
(1800 2250);
DISPLAY 0.978723 (1800 2250);
PAINT WHITE (1800 2250);
DISPLAY INVISIBLE (1800 2250);
FORCEPROP 2 LAST CDS_LOCATION R4405
J 0
(1800 2300);
DISPLAY 1.021277 (1800 2300);
DISPLAY INVISIBLE (1800 2300);
FORCEPROP 0 LAST $SEC 1
J 0
(1800 2250);
DISPLAY 0.680851 (1800 2250);
PAINT MONO (1800 2250);
DISPLAY INVISIBLE (1800 2250);
FORCEPROP 2 LAST CDS_SEC 1
J 0
(1800 2300);
DISPLAY 1.021277 (1800 2300);
DISPLAY INVISIBLE (1800 2300);
FORCEADD UNIVERSAL_POWER..1
(1750 2325);
FORCEPROP 3 LASTPIN (1750 2275) SIG_NAME P3V3\g
J 0
(1760 2285);
DISPLAY 0.659574 (1760 2285);
PAINT MONO (1760 2285);
DISPLAY INVISIBLE (1760 2285);
FORCEPROP 1 LAST HDL_POWER P3V3
J 1
(1750 2375);
DISPLAY 0.872340 (1750 2375);
PAINT GREEN (1750 2375);
FORCEPROP 2 LAST CDS_LIB logical_power
J 0
(1750 2325);
PAINT MONO (1750 2325);
DISPLAY INVISIBLE (1750 2325);
FORCEPROP 1 LAST PATH I28
J 0
(1800 2350);
DISPLAY 0.872340 (1800 2350);
PAINT AQUA (1800 2350);
DISPLAY INVISIBLE (1800 2350);
FORCEADD Q_RES..2
(1175 3750);
FORCEPROP 1 LAST PART_NUMBER CS11002FB07
J 0
(1215 3625);
DISPLAY 0.638298 (1215 3625);
DISPLAY INVISIBLE (1215 3625);
FORCEPROP 1 LAST VALUE 100
J 0
(1220 3825);
DISPLAY 0.638298 (1220 3825);
FORCEPROP 1 LAST TOLERANCE 1%
J 0
(1220 3775);
DISPLAY 0.638298 (1220 3775);
FORCEPROP 1 LAST PACK_TYPE 0402LF
J 0
(1215 3575);
DISPLAY 0.638298 (1215 3575);
FORCEPROP 1 LAST WATTAGE 1/16W
J 0
(1215 3725);
DISPLAY 0.638298 (1215 3725);
FORCEPROP 1 LAST MATERIAL CHIP
J 0
(1215 3675);
DISPLAY 0.638298 (1215 3675);
FORCEPROP 1 LAST $LOCATION R220
J 0
(1220 3875);
DISPLAY 0.978723 (1220 3875);
FORCEPROP 1 LASTPIN (1175 3850) $PN 1
J 0
(1180 3812);
DISPLAY 0.787234 (1180 3812);
FORCEPROP 1 LASTPIN (1175 3650) $PN 2
J 0
(1180 3660);
DISPLAY 0.787234 (1180 3660);
FORCEPROP 2 LAST CDS_LIB pure_quanta
J 0
(1175 3750);
PAINT MONO (1175 3750);
DISPLAY INVISIBLE (1175 3750);
FORCEPROP 1 LAST PATH I29
J 0
(1225 3925);
DISPLAY 0.978723 (1225 3925);
PAINT WHITE (1225 3925);
DISPLAY INVISIBLE (1225 3925);
FORCEPROP 2 LAST CDS_LOCATION R220
J 0
(1225 3975);
DISPLAY 1.021277 (1225 3975);
DISPLAY INVISIBLE (1225 3975);
FORCEPROP 2 LAST $SEC 1
J 0
(1225 3975);
DISPLAY 0.680851 (1225 3975);
PAINT MONO (1225 3975);
DISPLAY INVISIBLE (1225 3975);
FORCEPROP 2 LAST CDS_SEC 1
J 0
(1225 3975);
DISPLAY 1.021277 (1225 3975);
DISPLAY INVISIBLE (1225 3975);
FORCEADD OFFPAGE..1
(-2725 3400);
FORCEPROP 2 LAST $XR0 216 
J 0
(-2977 3400);
DISPLAY 0.638298 (-2977 3400);
PAINT MONO (-2977 3400);
FORCEPROP 1 LAST COMMENT_BODY TRUE
J 0
(-2600 3300);
DISPLAY 0.872340 (-2600 3300);
PAINT GREEN (-2600 3300);
DISPLAY INVISIBLE (-2600 3300);
FORCEPROP 1 LAST OFFPAGE TRUE
J 0
(-2400 3275);
DISPLAY 0.872340 (-2400 3275);
PAINT GREEN (-2400 3275);
DISPLAY INVISIBLE (-2400 3275);
FORCEPROP 2 LAST CDS_LIB standard
J 0
(-2725 3400);
PAINT MONO (-2725 3400);
DISPLAY INVISIBLE (-2725 3400);
FORCEPROP 2 LAST PATH I3
J 0
(-2975 3450);
DISPLAY 1.021277 (-2975 3450);
DISPLAY INVISIBLE (-2975 3450);
FORCEADD UNIVERSAL_POWER..1
(1175 4000);
FORCEPROP 3 LASTPIN (1175 3950) SIG_NAME PVNN_TERM_CPU1\g
J 0
(1185 3960);
DISPLAY 0.659574 (1185 3960);
PAINT MONO (1185 3960);
DISPLAY INVISIBLE (1185 3960);
FORCEPROP 1 LAST HDL_POWER PVNN_TERM_CPU1
J 1
(1175 4050);
DISPLAY 0.872340 (1175 4050);
PAINT GREEN (1175 4050);
FORCEPROP 2 LAST CDS_LIB logical_power
J 0
(1175 4000);
DISPLAY INVISIBLE (1175 4000);
FORCEPROP 1 LAST PATH I30
J 0
(1225 4025);
DISPLAY 0.872340 (1225 4025);
PAINT AQUA (1225 4025);
DISPLAY INVISIBLE (1225 4025);
FORCEADD Q_RES..1
(2400 1700);
FORCEPROP 1 LAST PART_NUMBER CS03322FB03
J 0
(2350 1800);
DISPLAY 0.787234 (2350 1800);
DISPLAY INVISIBLE (2350 1800);
FORCEPROP 1 LAST MATERIAL CHIP
J 0
(2400 1550);
DISPLAY 0.787234 (2400 1550);
FORCEPROP 1 LAST WATTAGE 1/16W
J 2
(2375 1550);
DISPLAY 0.787234 (2375 1550);
FORCEPROP 1 LAST VALUE 33.2
J 2
(2375 1600);
DISPLAY 0.787234 (2375 1600);
FORCEPROP 1 LAST TOLERANCE 1%
J 0
(2400 1600);
DISPLAY 0.787234 (2400 1600);
FORCEPROP 1 LAST PACK_TYPE 0402LF
J 0
(2650 1550);
DISPLAY 0.787234 (2650 1550);
FORCEPROP 1 LAST $LOCATION R4407
J 0
(2175 1700);
DISPLAY 0.638298 (2175 1700);
FORCEPROP 1 LASTPIN (2300 1700) $PN 1
J 0
(2312 1712);
DISPLAY 0.787234 (2312 1712);
PAINT MONO (2312 1712);
FORCEPROP 1 LASTPIN (2500 1700) $PN 2
J 0
(2462 1712);
DISPLAY 0.787234 (2462 1712);
PAINT MONO (2462 1712);
FORCEPROP 2 LAST CDS_LIB pure_quanta
J 0
(2400 1700);
DISPLAY INVISIBLE (2400 1700);
FORCEPROP 1 LAST PATH I31
J 0
(2350 1850);
DISPLAY 0.978723 (2350 1850);
PAINT WHITE (2350 1850);
DISPLAY INVISIBLE (2350 1850);
FORCEPROP 0 LAST CDS_LOCATION R4407
J 0
(2350 1850);
DISPLAY 1.021277 (2350 1850);
DISPLAY INVISIBLE (2350 1850);
FORCEPROP 0 LAST $SEC 1
J 0
(2350 1850);
DISPLAY 0.680851 (2350 1850);
PAINT MONO (2350 1850);
DISPLAY INVISIBLE (2350 1850);
FORCEPROP 0 LAST CDS_SEC 1
J 0
(2350 1850);
DISPLAY 1.021277 (2350 1850);
DISPLAY INVISIBLE (2350 1850);
FORCEADD OFFPAGE..2
(3225 1700);
FORCEPROP 2 LAST $XR0 216 
J 0
(3414 1700);
DISPLAY 0.638298 (3414 1700);
PAINT MONO (3414 1700);
FORCEPROP 1 LAST COMMENT_BODY TRUE
J 0
(3180 1605);
DISPLAY 0.872340 (3180 1605);
PAINT GREEN (3180 1605);
DISPLAY INVISIBLE (3180 1605);
FORCEPROP 1 LAST OFFPAGE TRUE
J 0
(3550 1575);
DISPLAY 0.872340 (3550 1575);
PAINT GREEN (3550 1575);
DISPLAY INVISIBLE (3550 1575);
FORCEPROP 2 LAST CDS_LIB standard
J 0
(3225 1700);
DISPLAY INVISIBLE (3225 1700);
FORCEPROP 2 LAST PATH I32
J 0
(3425 1750);
DISPLAY 1.021277 (3425 1750);
DISPLAY INVISIBLE (3425 1750);
FORCEADD Q_RES..1
(2450 3400);
FORCEPROP 1 LAST PART_NUMBER CS11002FB07
J 0
(2575 3300);
DISPLAY 0.638298 (2575 3300);
DISPLAY INVISIBLE (2575 3300);
FORCEPROP 1 LAST VALUE 100
J 2
(2425 3300);
DISPLAY 0.638298 (2425 3300);
FORCEPROP 1 LAST TOLERANCE 1%
J 0
(2450 3300);
DISPLAY 0.638298 (2450 3300);
FORCEPROP 1 LAST MATERIAL CHIP
J 0
(2450 3250);
DISPLAY 0.638298 (2450 3250);
FORCEPROP 1 LAST PACK_TYPE 0402LF
J 0
(2700 3250);
DISPLAY 0.638298 (2700 3250);
FORCEPROP 1 LAST WATTAGE 1/16W
J 2
(2425 3250);
DISPLAY 0.638298 (2425 3250);
FORCEPROP 1 LAST $LOCATION R4294
J 0
(2225 3400);
DISPLAY 0.638298 (2225 3400);
FORCEPROP 1 LASTPIN (2350 3400) $PN 1
J 0
(2362 3412);
DISPLAY 0.787234 (2362 3412);
PAINT MONO (2362 3412);
FORCEPROP 1 LASTPIN (2550 3400) $PN 2
J 0
(2512 3412);
DISPLAY 0.787234 (2512 3412);
PAINT MONO (2512 3412);
FORCEPROP 2 LAST CDS_LIB pure_quanta
J 0
(2450 3400);
DISPLAY INVISIBLE (2450 3400);
FORCEPROP 1 LAST PATH I33
J 0
(2400 3550);
DISPLAY 0.978723 (2400 3550);
PAINT WHITE (2400 3550);
DISPLAY INVISIBLE (2400 3550);
FORCEPROP 0 LAST CDS_LOCATION R4294
J 0
(2275 3450);
DISPLAY 1.021277 (2275 3450);
DISPLAY INVISIBLE (2275 3450);
FORCEPROP 0 LAST $SEC 1
J 0
(2275 3450);
DISPLAY 0.680851 (2275 3450);
PAINT MONO (2275 3450);
DISPLAY INVISIBLE (2275 3450);
FORCEPROP 0 LAST CDS_SEC 1
J 0
(2275 3450);
DISPLAY 1.021277 (2275 3450);
DISPLAY INVISIBLE (2275 3450);
FORCEADD Q_RES..1
(2450 4350);
FORCEPROP 1 LAST PART_NUMBER CS11002FB07
J 0
(2525 4250);
DISPLAY 0.638298 (2525 4250);
DISPLAY INVISIBLE (2525 4250);
FORCEPROP 1 LAST WATTAGE 1/16W
J 2
(2425 4200);
DISPLAY 0.638298 (2425 4200);
FORCEPROP 1 LAST VALUE 100
J 2
(2425 4250);
DISPLAY 0.638298 (2425 4250);
FORCEPROP 1 LAST TOLERANCE 1%
J 0
(2450 4250);
DISPLAY 0.638298 (2450 4250);
FORCEPROP 1 LAST MATERIAL CHIP
J 0
(2450 4200);
DISPLAY 0.638298 (2450 4200);
FORCEPROP 1 LAST PACK_TYPE 0402LF
J 0
(2575 4200);
DISPLAY 0.638298 (2575 4200);
FORCEPROP 1 LAST $LOCATION R4293
J 0
(2225 4350);
DISPLAY 0.638298 (2225 4350);
FORCEPROP 1 LASTPIN (2350 4350) $PN 1
J 0
(2362 4362);
DISPLAY 0.787234 (2362 4362);
PAINT MONO (2362 4362);
FORCEPROP 1 LASTPIN (2550 4350) $PN 2
J 0
(2512 4362);
DISPLAY 0.787234 (2512 4362);
PAINT MONO (2512 4362);
FORCEPROP 2 LAST CDS_LIB pure_quanta
J 0
(2450 4350);
DISPLAY INVISIBLE (2450 4350);
FORCEPROP 1 LAST PATH I34
J 0
(2400 4500);
DISPLAY 0.978723 (2400 4500);
PAINT WHITE (2400 4500);
DISPLAY INVISIBLE (2400 4500);
FORCEPROP 0 LAST CDS_LOCATION R4293
J 0
(2300 4400);
DISPLAY 1.021277 (2300 4400);
DISPLAY INVISIBLE (2300 4400);
FORCEPROP 0 LAST $SEC 1
J 0
(2300 4400);
DISPLAY 0.680851 (2300 4400);
PAINT MONO (2300 4400);
DISPLAY INVISIBLE (2300 4400);
FORCEPROP 0 LAST CDS_SEC 1
J 0
(2300 4400);
DISPLAY 1.021277 (2300 4400);
DISPLAY INVISIBLE (2300 4400);
FORCEADD OFFPAGE..2
(3650 3400);
FORCEPROP 2 LAST $XR0 45 
J 0
(3839 3400);
DISPLAY 0.638298 (3839 3400);
PAINT MONO (3839 3400);
FORCEPROP 1 LAST COMMENT_BODY TRUE
J 0
(3605 3305);
DISPLAY 0.872340 (3605 3305);
PAINT GREEN (3605 3305);
DISPLAY INVISIBLE (3605 3305);
FORCEPROP 1 LAST OFFPAGE TRUE
J 0
(3975 3275);
DISPLAY 0.872340 (3975 3275);
PAINT GREEN (3975 3275);
DISPLAY INVISIBLE (3975 3275);
FORCEPROP 2 LAST CDS_LIB standard
J 0
(3650 3400);
DISPLAY INVISIBLE (3650 3400);
FORCEPROP 2 LAST PATH I35
J 0
(3850 3450);
DISPLAY 1.021277 (3850 3450);
DISPLAY INVISIBLE (3850 3450);
FORCEADD OFFPAGE..2
(3650 4350);
FORCEPROP 2 LAST $XR0 14 
J 0
(3839 4350);
DISPLAY 0.638298 (3839 4350);
PAINT MONO (3839 4350);
FORCEPROP 1 LAST COMMENT_BODY TRUE
J 0
(3605 4255);
DISPLAY 0.872340 (3605 4255);
PAINT GREEN (3605 4255);
DISPLAY INVISIBLE (3605 4255);
FORCEPROP 1 LAST OFFPAGE TRUE
J 0
(3975 4225);
DISPLAY 0.872340 (3975 4225);
PAINT GREEN (3975 4225);
DISPLAY INVISIBLE (3975 4225);
FORCEPROP 2 LAST CDS_LIB standard
J 0
(3650 4350);
DISPLAY INVISIBLE (3650 4350);
FORCEPROP 2 LAST PATH I36
J 0
(3850 4400);
DISPLAY 1.021277 (3850 4400);
DISPLAY INVISIBLE (3850 4400);
FORCEADD Q_RES..2
(1175 4700);
FORCEPROP 1 LAST PART_NUMBER CS11002FB07
J 0
(1215 4575);
DISPLAY 0.638298 (1215 4575);
DISPLAY INVISIBLE (1215 4575);
FORCEPROP 1 LAST PACK_TYPE 0402LF
J 0
(1215 4525);
DISPLAY 0.638298 (1215 4525);
FORCEPROP 1 LAST MATERIAL CHIP
J 0
(1215 4625);
DISPLAY 0.638298 (1215 4625);
FORCEPROP 1 LAST WATTAGE 1/16W
J 0
(1215 4675);
DISPLAY 0.638298 (1215 4675);
FORCEPROP 1 LAST TOLERANCE 1%
J 0
(1220 4725);
DISPLAY 0.638298 (1220 4725);
FORCEPROP 1 LAST VALUE 100
J 0
(1220 4775);
DISPLAY 0.638298 (1220 4775);
FORCEPROP 1 LAST $LOCATION R219
J 0
(1220 4825);
DISPLAY 0.978723 (1220 4825);
FORCEPROP 1 LASTPIN (1175 4800) $PN 1
J 0
(1180 4762);
DISPLAY 0.787234 (1180 4762);
FORCEPROP 1 LASTPIN (1175 4600) $PN 2
J 0
(1180 4610);
DISPLAY 0.787234 (1180 4610);
FORCEPROP 2 LAST CDS_LIB pure_quanta
J 0
(1175 4700);
PAINT MONO (1175 4700);
DISPLAY INVISIBLE (1175 4700);
FORCEPROP 1 LAST PATH I37
J 0
(1225 4875);
DISPLAY 0.978723 (1225 4875);
PAINT WHITE (1225 4875);
DISPLAY INVISIBLE (1225 4875);
FORCEPROP 2 LAST CDS_LOCATION R219
J 0
(1225 4925);
DISPLAY 1.021277 (1225 4925);
DISPLAY INVISIBLE (1225 4925);
FORCEPROP 2 LAST $SEC 1
J 0
(1225 4925);
DISPLAY 0.680851 (1225 4925);
PAINT MONO (1225 4925);
DISPLAY INVISIBLE (1225 4925);
FORCEPROP 2 LAST CDS_SEC 1
J 0
(1225 4925);
DISPLAY 1.021277 (1225 4925);
DISPLAY INVISIBLE (1225 4925);
FORCEADD UNIVERSAL_POWER..1
(1175 4950);
FORCEPROP 3 LASTPIN (1175 4900) SIG_NAME PVNN_TERM_CPU0\g
J 0
(1185 4910);
DISPLAY 0.659574 (1185 4910);
PAINT MONO (1185 4910);
DISPLAY INVISIBLE (1185 4910);
FORCEPROP 1 LAST HDL_POWER PVNN_TERM_CPU0
J 1
(1175 5000);
DISPLAY 0.872340 (1175 5000);
PAINT GREEN (1175 5000);
FORCEPROP 2 LAST CDS_LIB logical_power
J 0
(1175 4950);
DISPLAY INVISIBLE (1175 4950);
FORCEPROP 1 LAST PATH I38
J 0
(1225 4975);
DISPLAY 0.872340 (1225 4975);
PAINT AQUA (1225 4975);
DISPLAY INVISIBLE (1225 4975);
FORCEADD OFFPAGE..1
(-2725 4350);
FORCEPROP 2 LAST $XR0 216 
J 0
(-2977 4350);
DISPLAY 0.638298 (-2977 4350);
PAINT MONO (-2977 4350);
FORCEPROP 1 LAST COMMENT_BODY TRUE
J 0
(-2600 4250);
DISPLAY 0.872340 (-2600 4250);
PAINT GREEN (-2600 4250);
DISPLAY INVISIBLE (-2600 4250);
FORCEPROP 1 LAST OFFPAGE TRUE
J 0
(-2400 4225);
DISPLAY 0.872340 (-2400 4225);
PAINT GREEN (-2400 4225);
DISPLAY INVISIBLE (-2400 4225);
FORCEPROP 2 LAST CDS_LIB standard
J 0
(-2725 4350);
PAINT MONO (-2725 4350);
DISPLAY INVISIBLE (-2725 4350);
FORCEPROP 2 LAST PATH I4
J 0
(-2975 4400);
DISPLAY 1.021277 (-2975 4400);
DISPLAY INVISIBLE (-2975 4400);
FORCEADD Q_RES..2
(-2000 1100);
FORCEPROP 1 LAST PART_NUMBER CS11002FB07
J 0
(-1975 925);
DISPLAY 0.510638 (-1975 925);
DISPLAY INVISIBLE (-1975 925);
FORCEPROP 1 LAST TOLERANCE 1%
J 0
(-1970 1075);
DISPLAY 0.510638 (-1970 1075);
FORCEPROP 1 LAST WATTAGE 1/16W
J 0
(-1975 1025);
DISPLAY 0.510638 (-1975 1025);
FORCEPROP 1 LAST VALUE 100
J 0
(-1970 1125);
DISPLAY 0.510638 (-1970 1125);
FORCEPROP 1 LAST PACK_TYPE 0402LF
J 0
(-1975 875);
DISPLAY 0.510638 (-1975 875);
FORCEPROP 1 LAST MATERIAL CHIP
J 0
(-1975 975);
DISPLAY 0.510638 (-1975 975);
FORCEPROP 1 LAST $LOCATION R4402
J 0
(-1970 1175);
DISPLAY 0.787234 (-1970 1175);
FORCEPROP 1 LASTPIN (-2000 1200) $PN 1
J 0
(-1995 1162);
DISPLAY 0.787234 (-1995 1162);
PAINT MONO (-1995 1162);
FORCEPROP 1 LASTPIN (-2000 1000) $PN 2
J 0
(-1995 1010);
DISPLAY 0.787234 (-1995 1010);
PAINT MONO (-1995 1010);
FORCEPROP 2 LAST CDS_LIB pure_quanta
J 0
(-2000 1100);
DISPLAY INVISIBLE (-2000 1100);
FORCEPROP 1 LAST PATH I5
J 0
(-1950 1275);
DISPLAY 0.978723 (-1950 1275);
PAINT WHITE (-1950 1275);
DISPLAY INVISIBLE (-1950 1275);
FORCEPROP 0 LAST CDS_LOCATION R4402
J 0
(-1950 1225);
DISPLAY 1.021277 (-1950 1225);
DISPLAY INVISIBLE (-1950 1225);
FORCEPROP 0 LAST $SEC 1
J 0
(-1950 1225);
DISPLAY 0.680851 (-1950 1225);
PAINT MONO (-1950 1225);
DISPLAY INVISIBLE (-1950 1225);
FORCEPROP 0 LAST CDS_SEC 1
J 0
(-1950 1225);
DISPLAY 1.021277 (-1950 1225);
DISPLAY INVISIBLE (-1950 1225);
FORCEADD Q_RES..1
(-1650 825);
FORCEPROP 1 LAST PART_NUMBER CS21502FB07
J 0
(-1700 925);
DISPLAY 0.787234 (-1700 925);
DISPLAY INVISIBLE (-1700 925);
FORCEPROP 1 LAST TOLERANCE 1%
J 0
(-1650 725);
DISPLAY 0.638298 (-1650 725);
FORCEPROP 1 LAST MATERIAL CHIP
J 0
(-1650 675);
DISPLAY 0.638298 (-1650 675);
FORCEPROP 1 LAST WATTAGE 1/16W
J 2
(-1675 675);
DISPLAY 0.638298 (-1675 675);
FORCEPROP 1 LAST PACK_TYPE 0402LF
J 0
(-1550 725);
DISPLAY 0.638298 (-1550 725);
FORCEPROP 1 LAST VALUE 1.5K
J 2
(-1675 725);
DISPLAY 0.638298 (-1675 725);
FORCEPROP 1 LAST LOCATION R204
J 0
(-1700 875);
DISPLAY 0.787234 (-1700 875);
FORCEPROP 1 LASTPIN (-1750 825) $PN 1
J 0
(-1738 837);
DISPLAY 0.787234 (-1738 837);
PAINT MONO (-1738 837);
FORCEPROP 1 LASTPIN (-1550 825) $PN 2
J 0
(-1588 837);
DISPLAY 0.787234 (-1588 837);
PAINT MONO (-1588 837);
FORCEPROP 2 LAST CDS_LIB pure_quanta
J 0
(-1650 825);
DISPLAY INVISIBLE (-1650 825);
FORCEPROP 1 LAST PATH I6
J 0
(-1700 975);
DISPLAY 0.978723 (-1700 975);
PAINT WHITE (-1700 975);
DISPLAY INVISIBLE (-1700 975);
FORCEPROP 0 LAST $SEC 1
J 0
(-1700 975);
DISPLAY 0.680851 (-1700 975);
PAINT MONO (-1700 975);
DISPLAY INVISIBLE (-1700 975);
FORCEPROP 0 LAST CDS_SEC 1
J 0
(-1700 975);
DISPLAY 1.021277 (-1700 975);
DISPLAY INVISIBLE (-1700 975);
FORCEADD UNIVERSAL_POWER..1
(-2000 1300);
FORCEPROP 3 LASTPIN (-2000 1250) SIG_NAME PVNN_TERM_CPU1\g
J 0
(-1990 1260);
DISPLAY 0.659574 (-1990 1260);
PAINT MONO (-1990 1260);
DISPLAY INVISIBLE (-1990 1260);
FORCEPROP 1 LAST HDL_POWER PVNN_TERM_CPU1
J 1
(-2000 1350);
DISPLAY 0.872340 (-2000 1350);
PAINT GREEN (-2000 1350);
FORCEPROP 2 LAST CDS_LIB logical_power
J 0
(-2000 1300);
DISPLAY INVISIBLE (-2000 1300);
FORCEPROP 1 LAST PATH I7
J 0
(-1950 1325);
DISPLAY 0.872340 (-1950 1325);
PAINT AQUA (-1950 1325);
DISPLAY INVISIBLE (-1950 1325);
FORCEADD Q_RES..2
(-2000 2450);
FORCEPROP 1 LAST PART_NUMBER CS11002FB07
J 0
(-1975 2275);
DISPLAY 0.510638 (-1975 2275);
DISPLAY INVISIBLE (-1975 2275);
FORCEPROP 1 LAST WATTAGE 1/16W
J 0
(-1975 2375);
DISPLAY 0.510638 (-1975 2375);
FORCEPROP 1 LAST VALUE 100
J 0
(-1970 2475);
DISPLAY 0.510638 (-1970 2475);
FORCEPROP 1 LAST PACK_TYPE 0402LF
J 0
(-1975 2225);
DISPLAY 0.510638 (-1975 2225);
FORCEPROP 1 LAST MATERIAL CHIP
J 0
(-1975 2325);
DISPLAY 0.510638 (-1975 2325);
FORCEPROP 1 LAST TOLERANCE 1%
J 0
(-1970 2425);
DISPLAY 0.510638 (-1970 2425);
FORCEPROP 1 LAST $LOCATION R4401
J 0
(-1970 2525);
DISPLAY 0.638298 (-1970 2525);
FORCEPROP 1 LASTPIN (-2000 2550) $PN 1
J 0
(-1995 2512);
DISPLAY 0.787234 (-1995 2512);
PAINT MONO (-1995 2512);
FORCEPROP 1 LASTPIN (-2000 2350) $PN 2
J 0
(-1995 2360);
DISPLAY 0.787234 (-1995 2360);
PAINT MONO (-1995 2360);
FORCEPROP 2 LAST CDS_LIB pure_quanta
J 0
(-2000 2450);
DISPLAY INVISIBLE (-2000 2450);
FORCEPROP 1 LAST PATH I8
J 0
(-1950 2625);
DISPLAY 0.978723 (-1950 2625);
PAINT WHITE (-1950 2625);
DISPLAY INVISIBLE (-1950 2625);
FORCEPROP 0 LAST CDS_LOCATION R4401
J 0
(-1950 2575);
DISPLAY 1.021277 (-1950 2575);
DISPLAY INVISIBLE (-1950 2575);
FORCEPROP 0 LAST $SEC 1
J 0
(-1950 2575);
DISPLAY 0.680851 (-1950 2575);
PAINT MONO (-1950 2575);
DISPLAY INVISIBLE (-1950 2575);
FORCEPROP 0 LAST CDS_SEC 1
J 0
(-1950 2575);
DISPLAY 1.021277 (-1950 2575);
DISPLAY INVISIBLE (-1950 2575);
FORCEADD Q_RES..1
(-1650 2175);
FORCEPROP 1 LAST PART_NUMBER CS21502FB07
J 0
(-1700 2275);
DISPLAY 0.787234 (-1700 2275);
DISPLAY INVISIBLE (-1700 2275);
FORCEPROP 1 LAST PACK_TYPE 0402LF
J 0
(-1550 2075);
DISPLAY 0.638298 (-1550 2075);
FORCEPROP 1 LAST TOLERANCE 1%
J 0
(-1650 2075);
DISPLAY 0.638298 (-1650 2075);
FORCEPROP 1 LAST MATERIAL CHIP
J 0
(-1650 2025);
DISPLAY 0.638298 (-1650 2025);
FORCEPROP 1 LAST WATTAGE 1/16W
J 2
(-1675 2025);
DISPLAY 0.638298 (-1675 2025);
FORCEPROP 1 LAST VALUE 1.5K
J 2
(-1675 2075);
DISPLAY 0.638298 (-1675 2075);
FORCEPROP 1 LAST LOCATION R203
J 0
(-1850 2175);
DISPLAY 0.638298 (-1850 2175);
FORCEPROP 1 LASTPIN (-1750 2175) $PN 1
J 0
(-1738 2187);
DISPLAY 0.787234 (-1738 2187);
PAINT MONO (-1738 2187);
FORCEPROP 1 LASTPIN (-1550 2175) $PN 2
J 0
(-1588 2187);
DISPLAY 0.787234 (-1588 2187);
PAINT MONO (-1588 2187);
FORCEPROP 2 LAST CDS_LIB pure_quanta
J 0
(-1650 2175);
DISPLAY INVISIBLE (-1650 2175);
FORCEPROP 1 LAST PATH I9
J 0
(-1700 2325);
DISPLAY 0.978723 (-1700 2325);
PAINT WHITE (-1700 2325);
DISPLAY INVISIBLE (-1700 2325);
FORCEPROP 0 LAST $SEC 1
J 0
(-1700 2325);
DISPLAY 0.680851 (-1700 2325);
PAINT MONO (-1700 2325);
DISPLAY INVISIBLE (-1700 2325);
FORCEPROP 0 LAST CDS_SEC 1
J 0
(-1700 2325);
DISPLAY 1.021277 (-1700 2325);
DISPLAY INVISIBLE (-1700 2325);
FORCEADD QUANTA_TITLE_BLOCK_C..1
(4550 -1450);
FORCEPROP 0 LAST CDS_CON_LAST_MODIFIED Fri Aug 25 14:01:42 2023
J 0
(2665 -1435);
PAINT MONO (2665 -1435);
DISPLAY INVISIBLE (2665 -1435);
FORCEPROP 2 LAST CUSTOM_TXT_CDS <XR_PAGE_TITLE>
J 0
(-3340 3800);
DISPLAY 0.638298 (-3340 3800);
PAINT PINK (-3340 3800);
DISPLAY INVISIBLE (-3340 3800);
FORCEPROP 2 LAST CUSTOM_TXT_CDS <CON_LAST_MODIFIED>
J 0
(2675 -1425);
DISPLAY 0.978723 (2675 -1425);
FORCEPROP 2 LAST CUSTOM_TXT_CDS <NAME_2>
J 0
(1375 -1400);
FORCEPROP 2 LAST CUSTOM_TXT_CDS <NAME_1>
J 0
(1375 -1275);
FORCEPROP 2 LAST CUSTOM_TXT_CDS <Q_NUMBER>
J 0
(3147 -1347);
DISPLAY 1.212766 (3147 -1347);
FORCEPROP 2 LAST CUSTOM_TXT_CDS <Q_PROJ>
J 0
(2168 -1348);
DISPLAY 1.212766 (2168 -1348);
FORCEPROP 2 LAST CUSTOM_TXT_CDS <Q_REV>
J 0
(4366 -1347);
DISPLAY 1.212766 (4366 -1347);
FORCEPROP 2 LAST CUSTOM_TXT_CDS <CON_PAGE_NUM> OF <CON_TOTAL_PAGES>
J 0
(4104 -1432);
DISPLAY 0.978723 (4104 -1432);
FORCEPROP 1 LAST Q_TITLE SPR CPU0 & 1- MEMHOT
J 0
(-4716 -1449);
DISPLAY 2.446809 (-4716 -1449);
PAINT GREEN (-4716 -1449);
FORCEPROP 1 LAST Q_DEPT 
J 1
(787 -1401);
DISPLAY 1.957447 (787 -1401);
PAINT GREEN (787 -1401);
FORCEPROP 2 LAST CDS_LIB pure_quanta
J 0
(4550 -1450);
PAINT MONO (4550 -1450);
DISPLAY INVISIBLE (4550 -1450);
FORCEPROP 1 LAST CDS_LMAN_SYM_OUTLINE -9475,6775,100,-125
J 0
(4550 -1450);
DISPLAY 0.468085 (4550 -1450);
PAINT GREEN (4550 -1450);
DISPLAY INVISIBLE (4550 -1450);
FORCEPROP 1 LAST COMMENT_BODY TRUE
J 0
(4562 -1463);
DISPLAY 0.978723 (4562 -1463);
PAINT GREEN (4562 -1463);
DISPLAY INVISIBLE (4562 -1463);
FORCEPROP 2 LAST PAGE_BORDER TRUE
J 0
(-3340 3800);
DISPLAY 0.638298 (-3340 3800);
PAINT PINK (-3340 3800);
DISPLAY INVISIBLE (-3340 3800);
FORCEPROP 2 LAST CDS_XR_PAGE_TITLE CR-122 : @S9S_MB_2U_LIB.S9S_MB_2U(SCH_1):PAGE122
J 0
(-3340 3800);
DISPLAY 0.638298 (-3340 3800);
PAINT PINK (-3340 3800);
DISPLAY INVISIBLE (-3340 3800);
WIRE 16 -1 (-2000 1250)(-2000 1200);
WIRE 16 -1 (-600 1025)(-600 925);
WIRE 16 -1 (-600 2375)(-600 2275);
WIRE 16 -1 (-2000 2600)(-2000 2550);
WIRE 16 -1 (1750 925)(1750 825);
WIRE 16 -1 (1750 2275)(1750 2175);
WIRE 16 -1 (1175 3950)(1175 3850);
WIRE 16 -1 (1175 4900)(1175 4800);
WIRE 16 -1 (1000 975)(1000 950);
WIRE 16 -1 (950 975)(1000 975);
WIRE 16 -1 (1000 2325)(1000 2300);
WIRE 16 -1 (950 2325)(1000 2325);
WIRE 16 -1 (2550 3400)(3600 3400);
FORCEPROP 2 LAST SIG_NAME H_CPU1_MEMHOT_IN_LVC1_N
J 0
(2925 3410);
DISPLAY 0.553191 (2925 3410);
PAINT WHITE (2925 3410);
WIRE 16 -1 (2550 4350)(3600 4350);
FORCEPROP 2 LAST SIG_NAME H_CPU0_MEMHOT_IN_LVC1_N
J 0
(2925 4360);
DISPLAY 0.553191 (2925 4360);
PAINT WHITE (2925 4360);
WIRE 16 -1 (3175 1700)(2500 1700);
FORCEPROP 2 LAST SIG_NAME H_CPU0_MEMHOT_OUT_LVC1_N
J 0
(2540 1710);
DISPLAY 0.553191 (2540 1710);
PAINT WHITE (2540 1710);
WIRE 16 -1 (1175 3650)(1175 3725);
WIRE 16 -1 (1175 3650)(1175 3400);
WIRE 16 -1 (1175 3400)(2350 3400);
FORCEPROP 2 LAST SIG_NAME H_CPU1_MEMHOT_IN_LVC1_R1_N
J 0
(1550 3410);
DISPLAY 0.553191 (1550 3410);
PAINT WHITE (1550 3410);
WIRE 16 -1 (-1375 3400)(1175 3400);
WIRE 16 -1 (1750 1975)(1750 1700);
WIRE 16 -1 (2300 1700)(1750 1700);
WIRE 16 -1 (950 1700)(950 1825);
WIRE 16 -1 (950 1700)(1750 1700);
FORCEPROP 2 LAST SIG_NAME H_CPU0_MEMHOT_OUT_VT_N
J 0
(1125 1710);
DISPLAY 0.553191 (1125 1710);
PAINT WHITE (1125 1710);
WIRE 16 -1 (950 2025)(950 2325);
WIRE 16 -1 (950 675)(950 975);
WIRE 16 -1 (225 1925)(800 1925);
FORCEPROP 2 LAST SIG_NAME H_CPU0_MEMHOT_OUT_R
J 0
(265 1935);
DISPLAY 0.510638 (265 1935);
PAINT WHITE (265 1935);
WIRE 16 -1 (225 575)(800 575);
FORCEPROP 2 LAST SIG_NAME H_CPU1_MEMHOT_OUT_R
J 0
(265 585);
DISPLAY 0.510638 (265 585);
PAINT WHITE (265 585);
WIRE 16 -1 (3175 350)(2500 350);
FORCEPROP 2 LAST SIG_NAME H_CPU1_MEMHOT_OUT_LVC1_N
J 0
(2540 360);
DISPLAY 0.553191 (2540 360);
PAINT WHITE (2540 360);
WIRE 16 -1 (1750 625)(1750 350);
WIRE 16 -1 (2300 350)(1750 350);
WIRE 16 -1 (950 350)(950 475);
WIRE 16 -1 (950 350)(1750 350);
FORCEPROP 2 LAST SIG_NAME H_CPU1_MEMHOT_OUT_VT_N
J 0
(1125 360);
DISPLAY 0.553191 (1125 360);
PAINT WHITE (1125 360);
WIRE 16 -1 (1175 4600)(1175 4350);
WIRE 16 -1 (1175 4350)(2350 4350);
FORCEPROP 2 LAST SIG_NAME H_CPU0_MEMHOT_IN_LVC1_R1_N
J 0
(1550 4360);
DISPLAY 0.553191 (1550 4360);
PAINT WHITE (1550 4360);
WIRE 16 -1 (-1375 4350)(1175 4350);
WIRE 16 2175 (-3525 0)(4175 0);
WIRE 16 2175 (4175 2725)(4175 0);
WIRE 16 2175 (-3525 2725)(-3525 0);
WIRE 16 2175 (-3525 2725)(4175 2725);
WIRE 16 -1 (-600 1925)(25 1925);
WIRE 16 -1 (-600 2075)(-600 1925);
FORCEPROP 2 LAST SIG_NAME H_CPU0_MEMHOT_OUT
J 0
(-560 1935);
DISPLAY 0.510638 (-560 1935);
PAINT WHITE (-560 1935);
WIRE 16 -1 (-600 575)(25 575);
WIRE 16 -1 (-600 725)(-600 575);
FORCEPROP 2 LAST SIG_NAME H_CPU1_MEMHOT_OUT
J 0
(-585 585);
DISPLAY 0.510638 (-585 585);
PAINT WHITE (-585 585);
WIRE 16 -1 (-1550 2175)(-750 2175);
FORCEPROP 2 LAST SIG_NAME H_CPU0_MEMHOT_OUT_VT_R_N
J 0
(-1510 2185);
DISPLAY 0.638298 (-1510 2185);
PAINT WHITE (-1510 2185);
WIRE 16 -1 (-1550 825)(-750 825);
FORCEPROP 2 LAST SIG_NAME H_CPU1_MEMHOT_OUT_VT_R_N
J 0
(-1510 835);
DISPLAY 0.638298 (-1510 835);
PAINT WHITE (-1510 835);
WIRE 16 -1 (-2000 2175)(-3025 2175);
FORCEPROP 2 LAST SIG_NAME H_CPU0_MEMHOT_OUT_LVC1_R_N
J 0
(-2960 2185);
DISPLAY 0.553191 (-2960 2185);
PAINT WHITE (-2960 2185);
WIRE 16 -1 (-2000 2350)(-2000 2175);
WIRE 16 -1 (-1750 2175)(-2000 2175);
WIRE 16 -1 (-2675 4350)(-1575 4350);
FORCEPROP 2 LAST SIG_NAME H_CPU0_MEMHOT_IN_LVC1_R_N
J 0
(-2610 4360);
DISPLAY 0.553191 (-2610 4360);
PAINT WHITE (-2610 4360);
WIRE 16 -1 (-2000 825)(-3025 825);
FORCEPROP 2 LAST SIG_NAME H_CPU1_MEMHOT_OUT_LVC1_R_N
J 0
(-2960 835);
DISPLAY 0.553191 (-2960 835);
PAINT WHITE (-2960 835);
WIRE 16 -1 (-2000 1000)(-2000 825);
WIRE 16 -1 (-1750 825)(-2000 825);
WIRE 16 -1 (-2675 3400)(-1575 3400);
FORCEPROP 2 LAST SIG_NAME H_CPU1_MEMHOT_IN_LVC1_R_N
J 0
(-2610 3410);
DISPLAY 0.553191 (-2610 3410);
PAINT WHITE (-2610 3410);
DOT 1 (-2000 825);
DOT 1 (-2000 2175);
DOT 1 (1750 350);
DOT 1 (1750 1700);
DOT 1 (1175 3400);
DOT 1 (1175 4350);
FORCENOTE
20211206 MODIFY FOR GT
(-4425 2975) 0;
DISPLAY LEFT (-4425 2975);
DISPLAY 2.510638 (-4425 2975);
PAINT PINK (-4425 2975);
FORCENOTE
20210907 MODIFY FOR GT
(-4700 4950) 0;
DISPLAY LEFT (-4700 4950);
DISPLAY 2.510638 (-4700 4950);
PAINT PINK (-4700 4950);
FORCENOTE
CPU0
(-3200 2225) 0;
DISPLAY LEFT (-3200 2225);
DISPLAY 1.276596 (-3200 2225);
PAINT SKYBLUE (-3200 2225);
FORCENOTE
CPU1
(-3225 925) 0;
DISPLAY LEFT (-3225 925);
DISPLAY 1.276596 (-3225 925);
PAINT SKYBLUE (-3225 925);
FORCENOTE
CPLD
(-2875 3500) 0;
DISPLAY LEFT (-2875 3500);
DISPLAY 1.276596 (-2875 3500);
PAINT SKYBLUE (-2875 3500);
FORCENOTE
CPLD
(-2875 4450) 0;
DISPLAY LEFT (-2875 4450);
DISPLAY 1.276596 (-2875 4450);
PAINT SKYBLUE (-2875 4450);
FORCENOTE
MEMHOT IN
(-3625 4675) 0;
DISPLAY LEFT (-3625 4675);
DISPLAY 2.510638 (-3625 4675);
PAINT SKYBLUE (-3625 4675);
FORCENOTE
20221208 CHANGE Q142,Q143 TO BA008470026
(-900 1350) 0;
DISPLAY LEFT (-900 1350);
DISPLAY 1.276596 (-900 1350);
PAINT PINK (-900 1350);
FORCENOTE
CPLD
(3700 325) 0;
DISPLAY LEFT (3700 325);
DISPLAY 1.276596 (3700 325);
PAINT SKYBLUE (3700 325);
FORCENOTE
CPU1
(2425 3600) 0;
DISPLAY LEFT (2425 3600);
DISPLAY 1.276596 (2425 3600);
PAINT SKYBLUE (2425 3600);
FORCENOTE
CPU0
(2425 4550) 0;
DISPLAY LEFT (2425 4550);
DISPLAY 1.276596 (2425 4550);
PAINT SKYBLUE (2425 4550);
FORCENOTE
CPLD
(3775 1675) 0;
DISPLAY LEFT (3775 1675);
DISPLAY 1.276596 (3775 1675);
PAINT SKYBLUE (3775 1675);
QUIT
